(kicad_pcb
	(version 20241229)
	(generator "pcbnew")
	(generator_version "9.0")
	(general
		(thickness 1.6296)
		(legacy_teardrops no)
	)
	(paper "A3")
	(title_block
		(title "Thunderbolt to 10GbE adapter")
		(date "2026-04-21")
		(rev "1.1.0")
		(company "Antmicro Ltd")
		(comment 1 "www.antmicro.com")
		(comment 9 "footprints 266-270 of 703")
	)
	(layers
		(0 "F.Cu" signal)
		(4 "In1.Cu" signal)
		(6 "In2.Cu" signal)
		(8 "In3.Cu" signal)
		(10 "In4.Cu" signal)
		(12 "In5.Cu" signal)
		(14 "In6.Cu" signal)
		(2 "B.Cu" signal)
		(9 "F.Adhes" user "F.Adhesive")
		(11 "B.Adhes" user "B.Adhesive")
		(13 "F.Paste" user)
		(15 "B.Paste" user)
		(5 "F.SilkS" user "F.Silkscreen")
		(7 "B.SilkS" user "B.Silkscreen")
		(1 "F.Mask" user)
		(3 "B.Mask" user)
		(17 "Dwgs.User" user "User.Drawings")
		(19 "Cmts.User" user "User.Comments")
		(21 "Eco1.User" user "User.Eco1")
		(23 "Eco2.User" user "User.Eco2")
		(25 "Edge.Cuts" user)
		(27 "Margin" user)
		(31 "F.CrtYd" user "F.Courtyard")
		(29 "B.CrtYd" user "B.Courtyard")
		(35 "F.Fab" user)
		(33 "B.Fab" user)
	)
	(footprint "antmicro-footprints:R_0402_1005Metric"
		(layer "F.Cu")
		(at 157.155 69.074999 90)
		(descr "Resistor SMD 0402")
		(tags "resistor SMD 0402")
		(property "Reference" "R170"
			(at 11.574999 20.295 90)
			(layer "F.SilkS")
			(effects
				(font
					(size 0.7 0.7)
					(thickness 0.15)
				)
			)
		)
		(property "Value" "R_10k_0402"
			(at -1.011843 1.772047 90)
			(layer "F.Fab")
			(effects
				(font
					(size 0.7 0.7)
					(thickness 0.15)
				)
				(justify left bottom)
			)
		)
		(property "Datasheet" "https://www.bourns.com/docs/product-datasheets/cr.pdf"
			(at 0 0 90)
			(layer "F.Fab")
			(hide yes)
			(effects
				(font
					(size 1.27 1.27)
					(thickness 0.15)
				)
			)
		)
		(property "Description" "SMD Chip Resistor, 10 kohm, ± 1%, 62.5 mW, 0402 [1005 Metric], Thick Film, General Purpose"
			(at 0 0 90)
			(layer "F.Fab")
			(hide yes)
			(effects
				(font
					(size 1.27 1.27)
					(thickness 0.15)
				)
			)
		)
		(property "MPN" "CR0402-FX-1002GLF"
			(at 0 0 90)
			(unlocked yes)
			(layer "F.Fab")
			(hide yes)
			(effects
				(font
					(size 1 1)
					(thickness 0.15)
				)
			)
		)
		(property "Manufacturer" "Bourns"
			(at 0 0 90)
			(unlocked yes)
			(layer "F.Fab")
			(hide yes)
			(effects
				(font
					(size 1 1)
					(thickness 0.15)
				)
			)
		)
		(property "License" "Apache-2.0"
			(at 0 0 90)
			(unlocked yes)
			(layer "F.Fab")
			(hide yes)
			(effects
				(font
					(size 1 1)
					(thickness 0.15)
				)
			)
		)
		(property "Author" "Antmicro"
			(at 0 0 90)
			(unlocked yes)
			(layer "F.Fab")
			(hide yes)
			(effects
				(font
					(size 1 1)
					(thickness 0.15)
				)
			)
		)
		(property "Val" "10k"
			(at 0 0 90)
			(unlocked yes)
			(layer "F.Fab")
			(hide yes)
			(effects
				(font
					(size 1 1)
					(thickness 0.15)
				)
			)
		)
		(property "Tolerance" "1%"
			(at 0 0 90)
			(unlocked yes)
			(layer "F.Fab")
			(hide yes)
			(effects
				(font
					(size 1 1)
					(thickness 0.15)
				)
			)
		)
		(sheetname "/X710-AT2 Misc/")
		(sheetfile "x710-at2-mics.kicad_sch")
		(attr smd)
		(fp_rect
			(start -0.925 -0.47)
			(end 0.925 0.47)
			(stroke
				(width 0.05)
				(type default)
			)
			(fill no)
			(layer "F.CrtYd")
		)
		(fp_rect
			(start -0.5 -0.25)
			(end 0.5 0.25)
			(stroke
				(width 0.15)
				(type solid)
			)
			(fill no)
			(layer "F.Fab")
		)
		(fp_text user "Author: Antmicro"
			(at -0.95 4.169 90)
			(layer "F.Fab")
			(effects
				(font
					(size 0.7 0.7)
					(thickness 0.15)
				)
				(justify left bottom)
			)
		)
		(fp_text user "${REFERENCE}"
			(at -0.95 3.168 90)
			(layer "F.Fab")
			(effects
				(font
					(size 0.7 0.7)
					(thickness 0.15)
				)
				(justify left bottom)
			)
		)
		(fp_text user "License: Apache-2.0"
			(at -0.95 5.169 90)
			(layer "F.Fab")
			(effects
				(font
					(size 0.7 0.7)
					(thickness 0.15)
				)
				(justify left bottom)
			)
		)
		(pad "1" smd roundrect
			(at -0.48 0 90)
			(size 0.59 0.64)
			(layers "F.Cu" "F.Mask" "F.Paste")
			(roundrect_rratio 0.25)
			(net 127 "/X710-AT2 Misc/~{DEV_DIS}")
			(pintype "passive")
		)
		(pad "2" smd roundrect
			(at 0.48 0 90)
			(size 0.59 0.64)
			(layers "F.Cu" "F.Mask" "F.Paste")
			(roundrect_rratio 0.25)
			(net 7 "+3V3")
			(pintype "passive")
		)
	)
	(footprint "antmicro-footprints:C_0402_1005Metric"
		(layer "F.Cu")
		(at 149.955 97.374999 -90)
		(descr "Capacitor SMD 0402")
		(tags "capacitor SMD 0402")
		(property "Reference" "C162"
			(at 19.625001 -23.294999 270)
			(layer "F.SilkS")
			(effects
				(font
					(size 0.7 0.7)
					(thickness 0.15)
				)
			)
		)
		(property "Value" "C_100n_0402"
			(at -1.022927 2.155213 270)
			(layer "F.Fab")
			(effects
				(font
					(size 0.7 0.7)
					(thickness 0.15)
				)
				(justify left bottom)
			)
		)
		(property "Datasheet" "https://www.murata.com/products/productdetail?partno=GRM155R61H104KE14%23"
			(at 0 0 270)
			(layer "F.Fab")
			(hide yes)
			(effects
				(font
					(size 1.27 1.27)
					(thickness 0.15)
				)
			)
		)
		(property "Description" "SMD Multilayer Ceramic Capacitor, 0.1 µF, 50 V, 0402 [1005 Metric], ± 10%, X5R, GRM Series"
			(at 0 0 270)
			(layer "F.Fab")
			(hide yes)
			(effects
				(font
					(size 1.27 1.27)
					(thickness 0.15)
				)
			)
		)
		(property "MPN" "GRM155R61H104KE14D"
			(at 0 0 270)
			(unlocked yes)
			(layer "F.Fab")
			(hide yes)
			(effects
				(font
					(size 1 1)
					(thickness 0.15)
				)
			)
		)
		(property "Val" "100n"
			(at 0 0 270)
			(unlocked yes)
			(layer "F.Fab")
			(hide yes)
			(effects
				(font
					(size 1 1)
					(thickness 0.15)
				)
			)
		)
		(property "Voltage" "50V"
			(at 0 0 270)
			(unlocked yes)
			(layer "F.Fab")
			(hide yes)
			(effects
				(font
					(size 1 1)
					(thickness 0.15)
				)
			)
		)
		(property "Dielectric" "X5R"
			(at 0 0 270)
			(unlocked yes)
			(layer "F.Fab")
			(hide yes)
			(effects
				(font
					(size 1 1)
					(thickness 0.15)
				)
			)
		)
		(property "Manufacturer" "Murata"
			(at 0 0 270)
			(unlocked yes)
			(layer "F.Fab")
			(hide yes)
			(effects
				(font
					(size 1 1)
					(thickness 0.15)
				)
			)
		)
		(property "License" "Apache-2.0"
			(at 0 0 270)
			(unlocked yes)
			(layer "F.Fab")
			(hide yes)
			(effects
				(font
					(size 1 1)
					(thickness 0.15)
				)
			)
		)
		(property "Author" "Antmicro"
			(at 0 0 270)
			(unlocked yes)
			(layer "F.Fab")
			(hide yes)
			(effects
				(font
					(size 1 1)
					(thickness 0.15)
				)
			)
		)
		(sheetname "/X710-AT2 power/")
		(sheetfile "x710-at2-power.kicad_sch")
		(attr smd)
		(fp_rect
			(start -0.925 -0.47)
			(end 0.925 0.47)
			(stroke
				(width 0.05)
				(type default)
			)
			(fill no)
			(layer "F.CrtYd")
		)
		(fp_line
			(start -0.494 0.248)
			(end -0.494 -0.25)
			(stroke
				(width 0.15)
				(type solid)
			)
			(layer "F.Fab")
		)
		(fp_line
			(start 0.504 0.248)
			(end -0.494 0.248)
			(stroke
				(width 0.15)
				(type solid)
			)
			(layer "F.Fab")
		)
		(fp_line
			(start -0.494 -0.25)
			(end 0.504 -0.25)
			(stroke
				(width 0.15)
				(type solid)
			)
			(layer "F.Fab")
		)
		(fp_line
			(start 0.504 -0.25)
			(end 0.504 0.248)
			(stroke
				(width 0.15)
				(type solid)
			)
			(layer "F.Fab")
		)
		(fp_text user "Author: Antmicro"
			(at -0.939 3.399 270)
			(layer "F.Fab")
			(effects
				(font
					(size 0.7 0.7)
					(thickness 0.15)
				)
				(justify left bottom)
			)
		)
		(fp_text user "License: Apache-2.0"
			(at -0.939 5.799 270)
			(layer "F.Fab")
			(effects
				(font
					(size 0.7 0.7)
					(thickness 0.15)
				)
				(justify left bottom)
			)
		)
		(fp_text user "${REFERENCE}"
			(at -0.939 4.599 270)
			(layer "F.Fab")
			(effects
				(font
					(size 0.7 0.7)
					(thickness 0.15)
				)
				(justify left bottom)
			)
		)
		(pad "1" smd roundrect
			(at -0.48 0 270)
			(size 0.59 0.64)
			(layers "F.Cu" "F.Mask" "F.Paste")
			(roundrect_rratio 0.25)
			(net 23 "GND")
			(pintype "passive")
		)
		(pad "2" smd roundrect
			(at 0.48 0 270)
			(size 0.59 0.64)
			(layers "F.Cu" "F.Mask" "F.Paste")
			(roundrect_rratio 0.25)
			(net 18 "+1V88")
			(pintype "passive")
		)
	)
	(footprint "antmicro-footprints:C_0402_1005Metric"
		(layer "F.Cu")
		(at 164.200001 109.850001 90)
		(descr "Capacitor SMD 0402")
		(tags "capacitor SMD 0402")
		(property "Reference" "C127"
			(at -16.799997 12 90)
			(layer "F.SilkS")
			(effects
				(font
					(size 0.7 0.7)
					(thickness 0.15)
				)
			)
		)
		(property "Value" "C_100n_0402"
			(at -1.022927 2.155213 90)
			(layer "F.Fab")
			(effects
				(font
					(size 0.7 0.7)
					(thickness 0.15)
				)
				(justify left bottom)
			)
		)
		(property "Datasheet" "https://www.murata.com/products/productdetail?partno=GRM155R61H104KE14%23"
			(at 0 0 90)
			(layer "F.Fab")
			(hide yes)
			(effects
				(font
					(size 1.27 1.27)
					(thickness 0.15)
				)
			)
		)
		(property "Description" "SMD Multilayer Ceramic Capacitor, 0.1 µF, 50 V, 0402 [1005 Metric], ± 10%, X5R, GRM Series"
			(at 0 0 90)
			(layer "F.Fab")
			(hide yes)
			(effects
				(font
					(size 1.27 1.27)
					(thickness 0.15)
				)
			)
		)
		(property "MPN" "GRM155R61H104KE14D"
			(at 0 0 90)
			(unlocked yes)
			(layer "F.Fab")
			(hide yes)
			(effects
				(font
					(size 1 1)
					(thickness 0.15)
				)
			)
		)
		(property "Manufacturer" "Murata"
			(at 0 0 90)
			(unlocked yes)
			(layer "F.Fab")
			(hide yes)
			(effects
				(font
					(size 1 1)
					(thickness 0.15)
				)
			)
		)
		(property "License" "Apache-2.0"
			(at 0 0 90)
			(unlocked yes)
			(layer "F.Fab")
			(hide yes)
			(effects
				(font
					(size 1 1)
					(thickness 0.15)
				)
			)
		)
		(property "Author" "Antmicro"
			(at 0 0 90)
			(unlocked yes)
			(layer "F.Fab")
			(hide yes)
			(effects
				(font
					(size 1 1)
					(thickness 0.15)
				)
			)
		)
		(property "Val" "100n"
			(at 0 0 90)
			(unlocked yes)
			(layer "F.Fab")
			(hide yes)
			(effects
				(font
					(size 1 1)
					(thickness 0.15)
				)
			)
		)
		(property "Voltage" "50V"
			(at 0 0 90)
			(unlocked yes)
			(layer "F.Fab")
			(hide yes)
			(effects
				(font
					(size 1 1)
					(thickness 0.15)
				)
			)
		)
		(property "Dielectric" "X5R"
			(at 0 0 90)
			(unlocked yes)
			(layer "F.Fab")
			(hide yes)
			(effects
				(font
					(size 1 1)
					(thickness 0.15)
				)
			)
		)
		(sheetname "/X710 DCDC converters/")
		(sheetfile "DCDC_converters_X710.kicad_sch")
		(attr smd)
		(fp_rect
			(start -0.925 -0.47)
			(end 0.925 0.47)
			(stroke
				(width 0.05)
				(type default)
			)
			(fill no)
			(layer "F.CrtYd")
		)
		(fp_line
			(start 0.504 -0.25)
			(end 0.504 0.248)
			(stroke
				(width 0.15)
				(type solid)
			)
			(layer "F.Fab")
		)
		(fp_line
			(start -0.494 -0.25)
			(end 0.504 -0.25)
			(stroke
				(width 0.15)
				(type solid)
			)
			(layer "F.Fab")
		)
		(fp_line
			(start 0.504 0.248)
			(end -0.494 0.248)
			(stroke
				(width 0.15)
				(type solid)
			)
			(layer "F.Fab")
		)
		(fp_line
			(start -0.494 0.248)
			(end -0.494 -0.25)
			(stroke
				(width 0.15)
				(type solid)
			)
			(layer "F.Fab")
		)
		(fp_text user "Author: Antmicro"
			(at -0.939 3.399 90)
			(layer "F.Fab")
			(effects
				(font
					(size 0.7 0.7)
					(thickness 0.15)
				)
				(justify left bottom)
			)
		)
		(fp_text user "${REFERENCE}"
			(at -0.939 4.599 90)
			(layer "F.Fab")
			(effects
				(font
					(size 0.7 0.7)
					(thickness 0.15)
				)
				(justify left bottom)
			)
		)
		(fp_text user "License: Apache-2.0"
			(at -0.939 5.799 90)
			(layer "F.Fab")
			(effects
				(font
					(size 0.7 0.7)
					(thickness 0.15)
				)
				(justify left bottom)
			)
		)
		(pad "1" smd roundrect
			(at -0.48 0 90)
			(size 0.59 0.64)
			(layers "F.Cu" "F.Mask" "F.Paste")
			(roundrect_rratio 0.25)
			(net 307 "/X710 DCDC converters/1V0_BST")
			(pintype "passive")
		)
		(pad "2" smd roundrect
			(at 0.48 0 90)
			(size 0.59 0.64)
			(layers "F.Cu" "F.Mask" "F.Paste")
			(roundrect_rratio 0.25)
			(net 310 "/X710 DCDC converters/1V0_SW")
			(pintype "passive")
		)
	)
	(footprint "antmicro-footprints:C_0603_1608Metric"
		(layer "F.Cu")
		(at 139.991421 120.15 -90)
		(descr "Capacitor SMD 0603")
		(tags "capacitor 0603")
		(property "Reference" "C80"
			(at -1.35 -0.55 270)
			(layer "F.SilkS")
			(effects
				(font
					(size 0.7 0.7)
					(thickness 0.15)
				)
				(justify left bottom)
			)
		)
		(property "Value" "C_22u_0603"
			(at -1.42757 1.770288 270)
			(layer "F.Fab")
			(effects
				(font
					(size 0.7 0.7)
					(thickness 0.15)
				)
				(justify left bottom)
			)
		)
		(property "Datasheet" "https://www.murata.com/products/productdetail?partno=GRM188R60J226MEA0%23"
			(at 0 0 270)
			(layer "F.Fab")
			(hide yes)
			(effects
				(font
					(size 1.27 1.27)
					(thickness 0.15)
				)
			)
		)
		(property "Description" "SMD Multilayer Ceramic Capacitor, 22 µF, 6.3 V, 0603 [1608 Metric], ± 20%, X5R, GRM Series"
			(at 0 0 270)
			(layer "F.Fab")
			(hide yes)
			(effects
				(font
					(size 1.27 1.27)
					(thickness 0.15)
				)
			)
		)
		(property "MPN" "GRM188R60J226MEA0D"
			(at 0 0 270)
			(unlocked yes)
			(layer "F.Fab")
			(hide yes)
			(effects
				(font
					(size 1 1)
					(thickness 0.15)
				)
			)
		)
		(property "Manufacturer" "Murata"
			(at 0 0 270)
			(unlocked yes)
			(layer "F.Fab")
			(hide yes)
			(effects
				(font
					(size 1 1)
					(thickness 0.15)
				)
			)
		)
		(property "License" "Apache-2.0"
			(at 0 0 270)
			(unlocked yes)
			(layer "F.Fab")
			(hide yes)
			(effects
				(font
					(size 1 1)
					(thickness 0.15)
				)
			)
		)
		(property "Val" "22u"
			(at 0 0 270)
			(unlocked yes)
			(layer "F.Fab")
			(hide yes)
			(effects
				(font
					(size 1 1)
					(thickness 0.15)
				)
			)
		)
		(property "Voltage" ""
			(at 0 0 270)
			(unlocked yes)
			(layer "F.Fab")
			(hide yes)
			(effects
				(font
					(size 1 1)
					(thickness 0.15)
				)
			)
		)
		(property "Dielectric" ""
			(at 0 0 270)
			(unlocked yes)
			(layer "F.Fab")
			(hide yes)
			(effects
				(font
					(size 1 1)
					(thickness 0.15)
				)
			)
		)
		(property "Author" "Antmicro"
			(at 0 0 270)
			(unlocked yes)
			(layer "F.Fab")
			(hide yes)
			(effects
				(font
					(size 1 1)
					(thickness 0.15)
				)
			)
		)
		(sheetname "/TB Controller - Power/")
		(sheetfile "tb-power.kicad_sch")
		(attr smd)
		(fp_line
			(start -0.15 0.4)
			(end 0.15 0.4)
			(stroke
				(width 0.15)
				(type solid)
			)
			(layer "F.SilkS")
		)
		(fp_line
			(start -0.15 -0.4)
			(end 0.15 -0.4)
			(stroke
				(width 0.15)
				(type solid)
			)
			(layer "F.SilkS")
		)
		(fp_rect
			(start -1.25 -0.65)
			(end 1.25 0.65)
			(stroke
				(width 0.05)
				(type solid)
			)
			(fill no)
			(layer "F.CrtYd")
		)
		(fp_rect
			(start -0.8 -0.4)
			(end 0.8 0.4)
			(stroke
				(width 0.15)
				(type solid)
			)
			(fill no)
			(layer "F.Fab")
		)
		(fp_text user "${REFERENCE}"
			(at -1.682 3.895 270)
			(layer "F.Fab")
			(effects
				(font
					(size 0.7 0.7)
					(thickness 0.15)
				)
				(justify left bottom)
			)
		)
		(fp_text user "License: Apache-2.0"
			(at -1.682 5.895 270)
			(layer "F.Fab")
			(effects
				(font
					(size 0.7 0.7)
					(thickness 0.15)
				)
				(justify left bottom)
			)
		)
		(fp_text user "Author: Antmicro"
			(at -1.682 4.894 270)
			(layer "F.Fab")
			(effects
				(font
					(size 0.7 0.7)
					(thickness 0.15)
				)
				(justify left bottom)
			)
		)
		(pad "1" smd roundrect
			(at -0.7 0 270)
			(size 0.8 1)
			(layers "F.Cu" "F.Mask" "F.Paste")
			(roundrect_rratio 0.2)
			(net 23 "GND")
			(pintype "passive")
		)
		(pad "2" smd roundrect
			(at 0.7 0 270)
			(size 0.8 1)
			(layers "F.Cu" "F.Mask" "F.Paste")
			(roundrect_rratio 0.2)
			(net 68 "/TB Controller - Power/VCC_0P9")
			(pintype "passive")
		)
	)
	(footprint "antmicro-footprints:R_0402_1005Metric"
		(layer "F.Cu")
		(at 159.249999 113.15)
		(descr "Resistor SMD 0402")
		(tags "resistor SMD 0402")
		(property "Reference" "R94"
			(at 12.950004 17.25 0)
			(layer "F.SilkS")
			(effects
				(font
					(size 0.7 0.7)
					(thickness 0.15)
				)
			)
		)
		(property "Value" "R_0R_0402"
			(at -1.011843 1.772047 0)
			(layer "F.Fab")
			(effects
				(font
					(size 0.7 0.7)
					(thickness 0.15)
				)
				(justify left bottom)
			)
		)
		(property "Datasheet" "https://industrial.panasonic.com/cdbs/www-data/pdf/RDA0000/AOA0000C301.pdf"
			(at 0 0 0)
			(layer "F.Fab")
			(hide yes)
			(effects
				(font
					(size 1.27 1.27)
					(thickness 0.15)
				)
			)
		)
		(property "Description" "SMD Chip Resistor, Jumper, 0 ohm, 100 mW, 0402 [1005 Metric], Thick Film, General Purpose"
			(at 0 0 0)
			(layer "F.Fab")
			(hide yes)
			(effects
				(font
					(size 1.27 1.27)
					(thickness 0.15)
				)
			)
		)
		(property "MPN" "ERJ2GE0R00X"
			(at 0 0 0)
			(unlocked yes)
			(layer "F.Fab")
			(hide yes)
			(effects
				(font
					(size 1 1)
					(thickness 0.15)
				)
			)
		)
		(property "Manufacturer" "Panasonic"
			(at 0 0 0)
			(unlocked yes)
			(layer "F.Fab")
			(hide yes)
			(effects
				(font
					(size 1 1)
					(thickness 0.15)
				)
			)
		)
		(property "License" "Apache-2.0"
			(at 0 0 0)
			(unlocked yes)
			(layer "F.Fab")
			(hide yes)
			(effects
				(font
					(size 1 1)
					(thickness 0.15)
				)
			)
		)
		(property "Author" "Antmicro"
			(at 0 0 0)
			(unlocked yes)
			(layer "F.Fab")
			(hide yes)
			(effects
				(font
					(size 1 1)
					(thickness 0.15)
				)
			)
		)
		(property "Val" "0R"
			(at 0 0 0)
			(unlocked yes)
			(layer "F.Fab")
			(hide yes)
			(effects
				(font
					(size 1 1)
					(thickness 0.15)
				)
			)
		)
		(property "Tolerance" "~"
			(at 0 0 0)
			(unlocked yes)
			(layer "F.Fab")
			(hide yes)
			(effects
				(font
					(size 1 1)
					(thickness 0.15)
				)
			)
		)
		(property "Current" "1A"
			(at 0 0 0)
			(unlocked yes)
			(layer "F.Fab")
			(hide yes)
			(effects
				(font
					(size 1 1)
					(thickness 0.15)
				)
			)
		)
		(sheetname "/X710 DCDC converters/")
		(sheetfile "DCDC_converters_X710.kicad_sch")
		(attr smd)
		(fp_rect
			(start -0.925 -0.47)
			(end 0.925 0.47)
			(stroke
				(width 0.05)
				(type default)
			)
			(fill no)
			(layer "F.CrtYd")
		)
		(fp_rect
			(start -0.5 -0.25)
			(end 0.5 0.25)
			(stroke
				(width 0.15)
				(type solid)
			)
			(fill no)
			(layer "F.Fab")
		)
		(fp_text user "License: Apache-2.0"
			(at -0.95 5.169 0)
			(layer "F.Fab")
			(effects
				(font
					(size 0.7 0.7)
					(thickness 0.15)
				)
				(justify left bottom)
			)
		)
		(fp_text user "${REFERENCE}"
			(at -0.95 3.168 0)
			(layer "F.Fab")
			(effects
				(font
					(size 0.7 0.7)
					(thickness 0.15)
				)
				(justify left bottom)
			)
		)
		(fp_text user "Author: Antmicro"
			(at -0.95 4.169 0)
			(layer "F.Fab")
			(effects
				(font
					(size 0.7 0.7)
					(thickness 0.15)
				)
				(justify left bottom)
			)
		)
		(pad "1" smd roundrect
			(at -0.48 0)
			(size 0.59 0.64)
			(layers "F.Cu" "F.Mask" "F.Paste")
			(roundrect_rratio 0.25)
			(net 380 "/X710 DCDC converters/1V88_PG")
			(pintype "passive")
		)
		(pad "2" smd roundrect
			(at 0.48 0)
			(size 0.59 0.64)
			(layers "F.Cu" "F.Mask" "F.Paste")
			(roundrect_rratio 0.25)
			(net 385 "/X710 DCDC converters/1V0_EN")
			(pintype "passive")
		)
	)
)
